(kicad_pcb
	(version 20260206)
	(generator "pcbnew")
	(generator_version "10.0")
	(general
		(thickness 1.6)
		(legacy_teardrops no)
	)
	(paper "A4")
	(title_block
		(title "04192023_DAF0TMB3IC0_F0TG_MB_C_brd_V02_OCP.brd")
		(comment 1 "Grand Teton / footprints 4342-4345 of 8354")
	)
	(layers
		(0 "F.Cu" signal "TOP")
		(4 "In1.Cu" signal "GND")
		(6 "In2.Cu" signal "IN1")
		(8 "In3.Cu" signal "GND1")
		(10 "In4.Cu" signal "IN2")
		(12 "In5.Cu" signal "GND2")
		(14 "In6.Cu" signal "IN3")
		(16 "In7.Cu" signal "GND3")
		(18 "In8.Cu" signal "VCC")
		(20 "In9.Cu" signal "VCC1")
		(22 "In10.Cu" signal "GND4")
		(24 "In11.Cu" signal "IN4")
		(26 "In12.Cu" signal "GND5")
		(28 "In13.Cu" signal "IN5")
		(30 "In14.Cu" signal "GND6")
		(32 "In15.Cu" signal "IN6")
		(34 "In16.Cu" signal "GND7")
		(2 "B.Cu" signal "BOTTOM")
		(9 "F.Adhes" user "F.Adhesive")
		(11 "B.Adhes" user "B.Adhesive")
		(13 "F.Paste" user "Package Geometry/Pastemask Top")
		(15 "B.Paste" user "Package Geometry/Pastemask Bottom")
		(5 "F.SilkS" user "Ref Des/Silkscreen Top")
		(7 "B.SilkS" user "Ref Des/Silkscreen Bottom")
		(1 "F.Mask" user "Board Geometry/Soldermask Top")
		(3 "B.Mask" user "Board Geometry/Soldermask Bottom")
		(17 "Dwgs.User" user "User.Drawings")
		(19 "Cmts.User" user "User.Comments")
		(21 "Eco1.User" user "User.Eco1")
		(23 "Eco2.User" user "User.Eco2")
		(25 "Edge.Cuts" user "Board Geometry/Outline")
		(27 "Margin" user)
		(31 "F.CrtYd" user "Package Geometry/Place Bound Top")
		(29 "B.CrtYd" user "Package Geometry/Place Bound Bottom")
		(35 "F.Fab" user "Ref Des/Assembly Top")
		(33 "B.Fab" user "Ref Des/Assembly Bottom")
	)
	(footprint ""
		(layer "F.Cu")
		(at 275.14169 -98.355404 180)
		(property "Reference" "R1644"
			(at 0 0 180)
			(layer "F.SilkS")
			(hide yes)
			(effects
				(font
					(size 1.27 1.27)
				)
			)
		)
		(property "Value" ""
			(at 0 0 180)
			(layer "F.Fab")
			(effects
				(font
					(size 1.27 1.27)
				)
			)
		)
		(duplicate_pad_numbers_are_jumpers no)
		(fp_line
			(start 0.7874 0.4064)
			(end -0.7874 0.4064)
			(stroke
				(width 0.1524)
				(type default)
			)
			(layer "F.SilkS")
		)
		(fp_line
			(start 0.7874 -0.4064)
			(end 0.7874 0.4064)
			(stroke
				(width 0.1524)
				(type default)
			)
			(layer "F.SilkS")
		)
		(fp_line
			(start -0.7874 0.4064)
			(end -0.7874 -0.4064)
			(stroke
				(width 0.1524)
				(type default)
			)
			(layer "F.SilkS")
		)
		(fp_line
			(start -0.7874 -0.4064)
			(end 0.7874 -0.4064)
			(stroke
				(width 0.1524)
				(type default)
			)
			(layer "F.SilkS")
		)
		(fp_line
			(start 0.67945 0.3048)
			(end 0.120396 0.3048)
			(stroke
				(width 0.1)
				(type default)
			)
			(layer "F.Fab")
		)
		(fp_line
			(start 0.67945 -0.3048)
			(end 0.67945 0.3048)
			(stroke
				(width 0.1)
				(type default)
			)
			(layer "F.Fab")
		)
		(fp_line
			(start 0.12065 -0.2794)
			(end 0.12065 -0.3048)
			(stroke
				(width 0.1)
				(type default)
			)
			(layer "F.Fab")
		)
		(fp_line
			(start 0.12065 -0.3048)
			(end 0.67945 -0.3048)
			(stroke
				(width 0.1)
				(type default)
			)
			(layer "F.Fab")
		)
		(fp_line
			(start 0.120396 0.3048)
			(end 0.120396 0.2794)
			(stroke
				(width 0.1)
				(type default)
			)
			(layer "F.Fab")
		)
		(fp_line
			(start 0.120396 0.2794)
			(end -0.12065 0.2794)
			(stroke
				(width 0.1)
				(type default)
			)
			(layer "F.Fab")
		)
		(fp_line
			(start -0.12065 0.3048)
			(end -0.67945 0.3048)
			(stroke
				(width 0.1)
				(type default)
			)
			(layer "F.Fab")
		)
		(fp_line
			(start -0.12065 0.2794)
			(end -0.12065 0.3048)
			(stroke
				(width 0.1)
				(type default)
			)
			(layer "F.Fab")
		)
		(fp_line
			(start -0.12065 -0.2794)
			(end 0.12065 -0.2794)
			(stroke
				(width 0.1)
				(type default)
			)
			(layer "F.Fab")
		)
		(fp_line
			(start -0.12065 -0.305054)
			(end -0.12065 -0.2794)
			(stroke
				(width 0.1)
				(type default)
			)
			(layer "F.Fab")
		)
		(fp_line
			(start -0.67945 0.3048)
			(end -0.67945 -0.305054)
			(stroke
				(width 0.1)
				(type default)
			)
			(layer "F.Fab")
		)
		(fp_line
			(start -0.67945 -0.305054)
			(end -0.12065 -0.305054)
			(stroke
				(width 0.1)
				(type default)
			)
			(layer "F.Fab")
		)
		(pad "1" smd circle
			(at -0.40005 0 180)
			(size 0 0)
			(layers "F.Cu" "F.Mask" "F.Paste")
			(net "JTAG_P1_R_TRST_N")
		)
		(pad "2" smd circle
			(at 0.40005 0 180)
			(size 0 0)
			(layers "F.Cu" "F.Mask" "F.Paste")
			(net "JTAG_CPU1_TRST_N")
		)
	)
	(footprint ""
		(layer "F.Cu")
		(at 70.662546 -384.10388 180)
		(property "Reference" "R6701"
			(at 0 0 180)
			(layer "F.SilkS")
			(hide yes)
			(effects
				(font
					(size 1.27 1.27)
				)
			)
		)
		(property "Value" ""
			(at 0 0 180)
			(layer "F.Fab")
			(effects
				(font
					(size 1.27 1.27)
				)
			)
		)
		(duplicate_pad_numbers_are_jumpers no)
		(fp_line
			(start 0.7874 0.4064)
			(end -0.7874 0.4064)
			(stroke
				(width 0.1524)
				(type default)
			)
			(layer "F.SilkS")
		)
		(fp_line
			(start 0.7874 -0.4064)
			(end 0.7874 0.4064)
			(stroke
				(width 0.1524)
				(type default)
			)
			(layer "F.SilkS")
		)
		(fp_line
			(start -0.7874 0.4064)
			(end -0.7874 -0.4064)
			(stroke
				(width 0.1524)
				(type default)
			)
			(layer "F.SilkS")
		)
		(fp_line
			(start -0.7874 -0.4064)
			(end 0.7874 -0.4064)
			(stroke
				(width 0.1524)
				(type default)
			)
			(layer "F.SilkS")
		)
		(fp_line
			(start 0.67945 0.3048)
			(end 0.120396 0.3048)
			(stroke
				(width 0.1)
				(type default)
			)
			(layer "F.Fab")
		)
		(fp_line
			(start 0.67945 -0.3048)
			(end 0.67945 0.3048)
			(stroke
				(width 0.1)
				(type default)
			)
			(layer "F.Fab")
		)
		(fp_line
			(start 0.12065 -0.2794)
			(end 0.12065 -0.3048)
			(stroke
				(width 0.1)
				(type default)
			)
			(layer "F.Fab")
		)
		(fp_line
			(start 0.12065 -0.3048)
			(end 0.67945 -0.3048)
			(stroke
				(width 0.1)
				(type default)
			)
			(layer "F.Fab")
		)
		(fp_line
			(start 0.120396 0.3048)
			(end 0.120396 0.2794)
			(stroke
				(width 0.1)
				(type default)
			)
			(layer "F.Fab")
		)
		(fp_line
			(start 0.120396 0.2794)
			(end -0.12065 0.2794)
			(stroke
				(width 0.1)
				(type default)
			)
			(layer "F.Fab")
		)
		(fp_line
			(start -0.12065 0.3048)
			(end -0.67945 0.3048)
			(stroke
				(width 0.1)
				(type default)
			)
			(layer "F.Fab")
		)
		(fp_line
			(start -0.12065 0.2794)
			(end -0.12065 0.3048)
			(stroke
				(width 0.1)
				(type default)
			)
			(layer "F.Fab")
		)
		(fp_line
			(start -0.12065 -0.2794)
			(end 0.12065 -0.2794)
			(stroke
				(width 0.1)
				(type default)
			)
			(layer "F.Fab")
		)
		(fp_line
			(start -0.12065 -0.305054)
			(end -0.12065 -0.2794)
			(stroke
				(width 0.1)
				(type default)
			)
			(layer "F.Fab")
		)
		(fp_line
			(start -0.67945 0.3048)
			(end -0.67945 -0.305054)
			(stroke
				(width 0.1)
				(type default)
			)
			(layer "F.Fab")
		)
		(fp_line
			(start -0.67945 -0.305054)
			(end -0.12065 -0.305054)
			(stroke
				(width 0.1)
				(type default)
			)
			(layer "F.Fab")
		)
		(pad "1" smd rect
			(at -0.40005 0)
			(size 0.4572 0.508)
			(layers "F.Cu" "F.Mask" "F.Paste")
			(net "P1V8_CPU1_RT_1D")
		)
		(pad "2" smd rect
			(at 0.40005 0)
			(size 0.4572 0.508)
			(layers "F.Cu" "F.Mask" "F.Paste")
			(net "P1V8_CPU1_RT0_1A_1D")
		)
	)
	(footprint ""
		(layer "F.Cu")
		(at 446.036954 -401.785328 90)
		(property "Reference" "PR6554"
			(at 0 0 90)
			(layer "F.SilkS")
			(hide yes)
			(effects
				(font
					(size 1.27 1.27)
				)
			)
		)
		(property "Value" ""
			(at 0 0 90)
			(layer "F.Fab")
			(effects
				(font
					(size 1.27 1.27)
				)
			)
		)
		(duplicate_pad_numbers_are_jumpers no)
		(fp_line
			(start 0.7874 -0.4064)
			(end 0.7874 0.4064)
			(stroke
				(width 0.1524)
				(type default)
			)
			(layer "F.SilkS")
		)
		(fp_line
			(start -0.7874 -0.4064)
			(end 0.7874 -0.4064)
			(stroke
				(width 0.1524)
				(type default)
			)
			(layer "F.SilkS")
		)
		(fp_line
			(start 0.7874 0.4064)
			(end -0.7874 0.4064)
			(stroke
				(width 0.1524)
				(type default)
			)
			(layer "F.SilkS")
		)
		(fp_line
			(start -0.7874 0.4064)
			(end -0.7874 -0.4064)
			(stroke
				(width 0.1524)
				(type default)
			)
			(layer "F.SilkS")
		)
		(fp_line
			(start -0.12065 -0.305054)
			(end -0.12065 -0.2794)
			(stroke
				(width 0.1)
				(type default)
			)
			(layer "F.Fab")
		)
		(fp_line
			(start -0.67945 -0.305054)
			(end -0.12065 -0.305054)
			(stroke
				(width 0.1)
				(type default)
			)
			(layer "F.Fab")
		)
		(fp_line
			(start 0.67945 -0.3048)
			(end 0.67945 0.3048)
			(stroke
				(width 0.1)
				(type default)
			)
			(layer "F.Fab")
		)
		(fp_line
			(start 0.12065 -0.3048)
			(end 0.67945 -0.3048)
			(stroke
				(width 0.1)
				(type default)
			)
			(layer "F.Fab")
		)
		(fp_line
			(start 0.12065 -0.2794)
			(end 0.12065 -0.3048)
			(stroke
				(width 0.1)
				(type default)
			)
			(layer "F.Fab")
		)
		(fp_line
			(start -0.12065 -0.2794)
			(end 0.12065 -0.2794)
			(stroke
				(width 0.1)
				(type default)
			)
			(layer "F.Fab")
		)
		(fp_line
			(start 0.120396 0.2794)
			(end -0.12065 0.2794)
			(stroke
				(width 0.1)
				(type default)
			)
			(layer "F.Fab")
		)
		(fp_line
			(start -0.12065 0.2794)
			(end -0.12065 0.3048)
			(stroke
				(width 0.1)
				(type default)
			)
			(layer "F.Fab")
		)
		(fp_line
			(start 0.67945 0.3048)
			(end 0.120396 0.3048)
			(stroke
				(width 0.1)
				(type default)
			)
			(layer "F.Fab")
		)
		(fp_line
			(start 0.120396 0.3048)
			(end 0.120396 0.2794)
			(stroke
				(width 0.1)
				(type default)
			)
			(layer "F.Fab")
		)
		(fp_line
			(start -0.12065 0.3048)
			(end -0.67945 0.3048)
			(stroke
				(width 0.1)
				(type default)
			)
			(layer "F.Fab")
		)
		(fp_line
			(start -0.67945 0.3048)
			(end -0.67945 -0.305054)
			(stroke
				(width 0.1)
				(type default)
			)
			(layer "F.Fab")
		)
		(pad "1" smd circle
			(at -0.40005 0 90)
			(size 0 0)
			(layers "F.Cu" "F.Mask" "F.Paste")
			(net "SW_P0V9_RETIMER_CPU0_BOOT1")
		)
		(pad "2" smd circle
			(at 0.40005 0 90)
			(size 0 0)
			(layers "F.Cu" "F.Mask" "F.Paste")
			(net "SW_P0V9_RETIMER_CPU0_BOOT1_RC")
		)
	)
	(footprint ""
		(layer "F.Cu")
		(at 133.127496 -370.57203 -90)
		(property "Reference" "C54"
			(at 0 0 270)
			(layer "F.SilkS")
			(hide yes)
			(effects
				(font
					(size 1.27 1.27)
				)
			)
		)
		(property "Value" ""
			(at 0 0 270)
			(layer "F.Fab")
			(effects
				(font
					(size 1.27 1.27)
				)
			)
		)
		(duplicate_pad_numbers_are_jumpers no)
		(fp_line
			(start -0.299974 0.150114)
			(end -0.299974 -0.150114)
			(stroke
				(width 0.1)
				(type default)
			)
			(layer "F.Fab")
		)
		(fp_line
			(start 0.299974 0.150114)
			(end -0.299974 0.150114)
			(stroke
				(width 0.1)
				(type default)
			)
			(layer "F.Fab")
		)
		(fp_line
			(start -0.299974 -0.150114)
			(end 0.299974 -0.150114)
			(stroke
				(width 0.1)
				(type default)
			)
			(layer "F.Fab")
		)
		(fp_line
			(start 0.299974 -0.150114)
			(end 0.299974 0.150114)
			(stroke
				(width 0.1)
				(type default)
			)
			(layer "F.Fab")
		)
		(pad "1" smd rect
			(at -0.2667 0 270)
			(size 0.3048 0.381)
			(layers "F.Cu" "F.Mask" "F.Paste")
			(net "P5E_CPU1_P3_TX_C_DN<12>")
		)
		(pad "2" smd rect
			(at 0.2667 0 270)
			(size 0.3048 0.381)
			(layers "F.Cu" "F.Mask" "F.Paste")
			(net "P5E_CPU1_P3_TX_DN<12>")
		)
	)
)
